(kicad_pcb
	(version 20260206)
	(generator "pcbnew")
	(generator_version "10.0")
	(general
		(thickness 1.6)
		(legacy_teardrops no)
	)
	(paper "A4")
	(title_block
		(title "04192023_DAF0TMB3IC0_F0TG_MB_C_brd_V02_OCP.brd")
		(comment 1 "Grand Teton / footprints 3135-3137 of 8354")
	)
	(layers
		(0 "F.Cu" signal "TOP")
		(4 "In1.Cu" signal "GND")
		(6 "In2.Cu" signal "IN1")
		(8 "In3.Cu" signal "GND1")
		(10 "In4.Cu" signal "IN2")
		(12 "In5.Cu" signal "GND2")
		(14 "In6.Cu" signal "IN3")
		(16 "In7.Cu" signal "GND3")
		(18 "In8.Cu" signal "VCC")
		(20 "In9.Cu" signal "VCC1")
		(22 "In10.Cu" signal "GND4")
		(24 "In11.Cu" signal "IN4")
		(26 "In12.Cu" signal "GND5")
		(28 "In13.Cu" signal "IN5")
		(30 "In14.Cu" signal "GND6")
		(32 "In15.Cu" signal "IN6")
		(34 "In16.Cu" signal "GND7")
		(2 "B.Cu" signal "BOTTOM")
		(9 "F.Adhes" user "F.Adhesive")
		(11 "B.Adhes" user "B.Adhesive")
		(13 "F.Paste" user "Package Geometry/Pastemask Top")
		(15 "B.Paste" user "Package Geometry/Pastemask Bottom")
		(5 "F.SilkS" user "Ref Des/Silkscreen Top")
		(7 "B.SilkS" user "Ref Des/Silkscreen Bottom")
		(1 "F.Mask" user "Board Geometry/Soldermask Top")
		(3 "B.Mask" user "Board Geometry/Soldermask Bottom")
		(17 "Dwgs.User" user "User.Drawings")
		(19 "Cmts.User" user "User.Comments")
		(21 "Eco1.User" user "User.Eco1")
		(23 "Eco2.User" user "User.Eco2")
		(25 "Edge.Cuts" user "Board Geometry/Outline")
		(27 "Margin" user)
		(31 "F.CrtYd" user "Package Geometry/Place Bound Top")
		(29 "B.CrtYd" user "Package Geometry/Place Bound Bottom")
		(35 "F.Fab" user "Ref Des/Assembly Top")
		(33 "B.Fab" user "Ref Des/Assembly Bottom")
	)
	(footprint ""
		(layer "F.Cu")
		(at 10.066782 -409.675584 180)
		(property "Reference" "PC514"
			(at 0 0 180)
			(layer "F.SilkS")
			(hide yes)
			(effects
				(font
					(size 1.27 1.27)
				)
			)
		)
		(property "Value" ""
			(at 0 0 180)
			(layer "F.Fab")
			(effects
				(font
					(size 1.27 1.27)
				)
			)
		)
		(duplicate_pad_numbers_are_jumpers no)
		(fp_line
			(start 0.7874 0.4064)
			(end -0.7874 0.4064)
			(stroke
				(width 0.1524)
				(type default)
			)
			(layer "F.SilkS")
		)
		(fp_line
			(start 0.7874 -0.4064)
			(end 0.7874 0.4064)
			(stroke
				(width 0.1524)
				(type default)
			)
			(layer "F.SilkS")
		)
		(fp_line
			(start -0.7874 0.4064)
			(end -0.7874 -0.4064)
			(stroke
				(width 0.1524)
				(type default)
			)
			(layer "F.SilkS")
		)
		(fp_line
			(start -0.7874 -0.4064)
			(end 0.7874 -0.4064)
			(stroke
				(width 0.1524)
				(type default)
			)
			(layer "F.SilkS")
		)
		(fp_line
			(start 0.67945 0.3048)
			(end 0.120396 0.3048)
			(stroke
				(width 0.1)
				(type default)
			)
			(layer "F.Fab")
		)
		(fp_line
			(start 0.67945 -0.3048)
			(end 0.67945 0.3048)
			(stroke
				(width 0.1)
				(type default)
			)
			(layer "F.Fab")
		)
		(fp_line
			(start 0.12065 -0.2794)
			(end 0.12065 -0.3048)
			(stroke
				(width 0.1)
				(type default)
			)
			(layer "F.Fab")
		)
		(fp_line
			(start 0.12065 -0.3048)
			(end 0.67945 -0.3048)
			(stroke
				(width 0.1)
				(type default)
			)
			(layer "F.Fab")
		)
		(fp_line
			(start 0.120396 0.3048)
			(end 0.120396 0.2794)
			(stroke
				(width 0.1)
				(type default)
			)
			(layer "F.Fab")
		)
		(fp_line
			(start 0.120396 0.2794)
			(end -0.12065 0.2794)
			(stroke
				(width 0.1)
				(type default)
			)
			(layer "F.Fab")
		)
		(fp_line
			(start -0.12065 0.3048)
			(end -0.67945 0.3048)
			(stroke
				(width 0.1)
				(type default)
			)
			(layer "F.Fab")
		)
		(fp_line
			(start -0.12065 0.2794)
			(end -0.12065 0.3048)
			(stroke
				(width 0.1)
				(type default)
			)
			(layer "F.Fab")
		)
		(fp_line
			(start -0.12065 -0.2794)
			(end 0.12065 -0.2794)
			(stroke
				(width 0.1)
				(type default)
			)
			(layer "F.Fab")
		)
		(fp_line
			(start -0.12065 -0.305054)
			(end -0.12065 -0.2794)
			(stroke
				(width 0.1)
				(type default)
			)
			(layer "F.Fab")
		)
		(fp_line
			(start -0.67945 0.3048)
			(end -0.67945 -0.305054)
			(stroke
				(width 0.1)
				(type default)
			)
			(layer "F.Fab")
		)
		(fp_line
			(start -0.67945 -0.305054)
			(end -0.12065 -0.305054)
			(stroke
				(width 0.1)
				(type default)
			)
			(layer "F.Fab")
		)
		(pad "1" smd circle
			(at -0.40005 0 180)
			(size 0 0)
			(layers "F.Cu" "F.Mask" "F.Paste")
			(net "P0V9_RETIMER_CPU1_VMON")
		)
		(pad "2" smd circle
			(at 0.40005 0 180)
			(size 0 0)
			(layers "F.Cu" "F.Mask" "F.Paste")
			(net "GND")
		)
	)
	(footprint ""
		(layer "F.Cu")
		(at 468.957914 -42.121836 180)
		(property "Reference" "R4061"
			(at 0 0 180)
			(layer "F.SilkS")
			(hide yes)
			(effects
				(font
					(size 1.27 1.27)
				)
			)
		)
		(property "Value" ""
			(at 0 0 180)
			(layer "F.Fab")
			(effects
				(font
					(size 1.27 1.27)
				)
			)
		)
		(duplicate_pad_numbers_are_jumpers no)
		(fp_line
			(start 0.7874 0.4064)
			(end -0.7874 0.4064)
			(stroke
				(width 0.1524)
				(type default)
			)
			(layer "F.SilkS")
		)
		(fp_line
			(start 0.7874 -0.4064)
			(end 0.7874 0.4064)
			(stroke
				(width 0.1524)
				(type default)
			)
			(layer "F.SilkS")
		)
		(fp_line
			(start -0.7874 0.4064)
			(end -0.7874 -0.4064)
			(stroke
				(width 0.1524)
				(type default)
			)
			(layer "F.SilkS")
		)
		(fp_line
			(start -0.7874 -0.4064)
			(end 0.7874 -0.4064)
			(stroke
				(width 0.1524)
				(type default)
			)
			(layer "F.SilkS")
		)
		(fp_line
			(start 0.67945 0.3048)
			(end 0.120396 0.3048)
			(stroke
				(width 0.1)
				(type default)
			)
			(layer "F.Fab")
		)
		(fp_line
			(start 0.67945 -0.3048)
			(end 0.67945 0.3048)
			(stroke
				(width 0.1)
				(type default)
			)
			(layer "F.Fab")
		)
		(fp_line
			(start 0.12065 -0.2794)
			(end 0.12065 -0.3048)
			(stroke
				(width 0.1)
				(type default)
			)
			(layer "F.Fab")
		)
		(fp_line
			(start 0.12065 -0.3048)
			(end 0.67945 -0.3048)
			(stroke
				(width 0.1)
				(type default)
			)
			(layer "F.Fab")
		)
		(fp_line
			(start 0.120396 0.3048)
			(end 0.120396 0.2794)
			(stroke
				(width 0.1)
				(type default)
			)
			(layer "F.Fab")
		)
		(fp_line
			(start 0.120396 0.2794)
			(end -0.12065 0.2794)
			(stroke
				(width 0.1)
				(type default)
			)
			(layer "F.Fab")
		)
		(fp_line
			(start -0.12065 0.3048)
			(end -0.67945 0.3048)
			(stroke
				(width 0.1)
				(type default)
			)
			(layer "F.Fab")
		)
		(fp_line
			(start -0.12065 0.2794)
			(end -0.12065 0.3048)
			(stroke
				(width 0.1)
				(type default)
			)
			(layer "F.Fab")
		)
		(fp_line
			(start -0.12065 -0.2794)
			(end 0.12065 -0.2794)
			(stroke
				(width 0.1)
				(type default)
			)
			(layer "F.Fab")
		)
		(fp_line
			(start -0.12065 -0.305054)
			(end -0.12065 -0.2794)
			(stroke
				(width 0.1)
				(type default)
			)
			(layer "F.Fab")
		)
		(fp_line
			(start -0.67945 0.3048)
			(end -0.67945 -0.305054)
			(stroke
				(width 0.1)
				(type default)
			)
			(layer "F.Fab")
		)
		(fp_line
			(start -0.67945 -0.305054)
			(end -0.12065 -0.305054)
			(stroke
				(width 0.1)
				(type default)
			)
			(layer "F.Fab")
		)
		(pad "1" smd circle
			(at -0.40005 0 180)
			(size 0 0)
			(layers "F.Cu" "F.Mask" "F.Paste")
			(net "P12V_OCP_SFF_EN_R")
		)
		(pad "2" smd circle
			(at 0.40005 0 180)
			(size 0 0)
			(layers "F.Cu" "F.Mask" "F.Paste")
			(net "P12V_OCP_EN_1_R")
		)
	)
	(footprint ""
		(layer "F.Cu")
		(at 22.036278 -435.948074 180)
		(property "Reference" "R2991"
			(at 0 0 180)
			(layer "F.SilkS")
			(hide yes)
			(effects
				(font
					(size 1.27 1.27)
				)
			)
		)
		(property "Value" ""
			(at 0 0 180)
			(layer "F.Fab")
			(effects
				(font
					(size 1.27 1.27)
				)
			)
		)
		(duplicate_pad_numbers_are_jumpers no)
		(fp_line
			(start 0.7874 0.4064)
			(end -0.7874 0.4064)
			(stroke
				(width 0.1524)
				(type default)
			)
			(layer "F.SilkS")
		)
		(fp_line
			(start 0.7874 -0.4064)
			(end 0.7874 0.4064)
			(stroke
				(width 0.1524)
				(type default)
			)
			(layer "F.SilkS")
		)
		(fp_line
			(start -0.7874 0.4064)
			(end -0.7874 -0.4064)
			(stroke
				(width 0.1524)
				(type default)
			)
			(layer "F.SilkS")
		)
		(fp_line
			(start -0.7874 -0.4064)
			(end 0.7874 -0.4064)
			(stroke
				(width 0.1524)
				(type default)
			)
			(layer "F.SilkS")
		)
		(fp_line
			(start 0.67945 0.3048)
			(end 0.120396 0.3048)
			(stroke
				(width 0.1)
				(type default)
			)
			(layer "F.Fab")
		)
		(fp_line
			(start 0.67945 -0.3048)
			(end 0.67945 0.3048)
			(stroke
				(width 0.1)
				(type default)
			)
			(layer "F.Fab")
		)
		(fp_line
			(start 0.12065 -0.2794)
			(end 0.12065 -0.3048)
			(stroke
				(width 0.1)
				(type default)
			)
			(layer "F.Fab")
		)
		(fp_line
			(start 0.12065 -0.3048)
			(end 0.67945 -0.3048)
			(stroke
				(width 0.1)
				(type default)
			)
			(layer "F.Fab")
		)
		(fp_line
			(start 0.120396 0.3048)
			(end 0.120396 0.2794)
			(stroke
				(width 0.1)
				(type default)
			)
			(layer "F.Fab")
		)
		(fp_line
			(start 0.120396 0.2794)
			(end -0.12065 0.2794)
			(stroke
				(width 0.1)
				(type default)
			)
			(layer "F.Fab")
		)
		(fp_line
			(start -0.12065 0.3048)
			(end -0.67945 0.3048)
			(stroke
				(width 0.1)
				(type default)
			)
			(layer "F.Fab")
		)
		(fp_line
			(start -0.12065 0.2794)
			(end -0.12065 0.3048)
			(stroke
				(width 0.1)
				(type default)
			)
			(layer "F.Fab")
		)
		(fp_line
			(start -0.12065 -0.2794)
			(end 0.12065 -0.2794)
			(stroke
				(width 0.1)
				(type default)
			)
			(layer "F.Fab")
		)
		(fp_line
			(start -0.12065 -0.305054)
			(end -0.12065 -0.2794)
			(stroke
				(width 0.1)
				(type default)
			)
			(layer "F.Fab")
		)
		(fp_line
			(start -0.67945 0.3048)
			(end -0.67945 -0.305054)
			(stroke
				(width 0.1)
				(type default)
			)
			(layer "F.Fab")
		)
		(fp_line
			(start -0.67945 -0.305054)
			(end -0.12065 -0.305054)
			(stroke
				(width 0.1)
				(type default)
			)
			(layer "F.Fab")
		)
		(pad "1" smd circle
			(at -0.40005 0 180)
			(size 0 0)
			(layers "F.Cu" "F.Mask" "F.Paste")
			(net "SMB_2_BMC_GPU_BUF_R_SDA")
		)
		(pad "2" smd circle
			(at 0.40005 0 180)
			(size 0 0)
			(layers "F.Cu" "F.Mask" "F.Paste")
			(net "SMB_2_BMC_GPU_BUF_SDA")
		)
	)
)
